# S9S_MB_2U (Grand Teton) — schematic netlist excerpt (pin names and nets, part order shuffled) for the footprints in the layout excerpt that follows; sources: Cadence DE-HDL packaged netlist, KiCad conversion of 03242023_DA0F0TMBIJ0_F0T_Motherboard_J_brd_V01_OCP.brd

R2838  Q_RES  100K 1% CHIP  pkg 0402LF  page 148 : A = FM_SWB_PWRGD ; B = GND
R2980  Q_RES  1K 1% CHIP  pkg 0402LF  page 195 : A = FM_BOARD_SKU_ID2 ; B = GND

(kicad_pcb
	(version 20260206)
	(generator "pcbnew")
	(generator_version "10.0")
	(general
		(thickness 1.6)
		(legacy_teardrops no)
	)
	(paper "A4")
	(title_block
		(title "03242023_DA0F0TMBIJ0_F0T_Motherboard_J_brd_V01_OCP.brd")
		(comment 1 "Grand Teton / footprints 2469-2470 of 6105")
	)
	(layers
		(0 "F.Cu" signal "TOP")
		(4 "In1.Cu" signal "GND")
		(6 "In2.Cu" signal "IN1")
		(8 "In3.Cu" signal "GND1")
		(10 "In4.Cu" signal "IN2")
		(12 "In5.Cu" signal "GND2")
		(14 "In6.Cu" signal "IN3")
		(16 "In7.Cu" signal "GND3")
		(18 "In8.Cu" signal "VCC")
		(20 "In9.Cu" signal "VCC1")
		(22 "In10.Cu" signal "GND4")
		(24 "In11.Cu" signal "IN4")
		(26 "In12.Cu" signal "GND5")
		(28 "In13.Cu" signal "IN5")
		(30 "In14.Cu" signal "GND6")
		(32 "In15.Cu" signal "IN6")
		(34 "In16.Cu" signal "GND7")
		(2 "B.Cu" signal "BOTTOM")
		(9 "F.Adhes" user "F.Adhesive")
		(11 "B.Adhes" user "B.Adhesive")
		(13 "F.Paste" user "Package Geometry/Pastemask Top")
		(15 "B.Paste" user "Package Geometry/Pastemask Bottom")
		(5 "F.SilkS" user "Ref Des/Silkscreen Top")
		(7 "B.SilkS" user "Ref Des/Silkscreen Bottom")
		(1 "F.Mask" user "Board Geometry/Soldermask Top")
		(3 "B.Mask" user "Board Geometry/Soldermask Bottom")
		(17 "Dwgs.User" user "User.Drawings")
		(19 "Cmts.User" user "User.Comments")
		(21 "Eco1.User" user "User.Eco1")
		(23 "Eco2.User" user "User.Eco2")
		(25 "Edge.Cuts" user "Board Geometry/Outline")
		(27 "Margin" user)
		(31 "F.CrtYd" user "Package Geometry/Place Bound Top")
		(29 "B.CrtYd" user "Package Geometry/Place Bound Bottom")
		(35 "F.Fab" user "Ref Des/Assembly Top")
		(33 "B.Fab" user "Ref Des/Assembly Bottom")
	)
	(footprint ""
		(layer "F.Cu")
		(at 424.204892 -387.314948 180)
		(property "Reference" "R2838"
			(at 0 0 180)
			(layer "F.SilkS")
			(hide yes)
			(effects
				(font
					(size 1.27 1.27)
				)
			)
		)
		(property "Value" ""
			(at 0 0 180)
			(layer "F.Fab")
			(effects
				(font
					(size 1.27 1.27)
				)
			)
		)
		(duplicate_pad_numbers_are_jumpers no)
		(fp_line
			(start 0.7874 0.4064)
			(end -0.7874 0.4064)
			(stroke
				(width 0.1524)
				(type default)
			)
			(layer "F.SilkS")
		)
		(fp_line
			(start 0.7874 -0.4064)
			(end 0.7874 0.4064)
			(stroke
				(width 0.1524)
				(type default)
			)
			(layer "F.SilkS")
		)
		(fp_line
			(start -0.7874 0.4064)
			(end -0.7874 -0.4064)
			(stroke
				(width 0.1524)
				(type default)
			)
			(layer "F.SilkS")
		)
		(fp_line
			(start -0.7874 -0.4064)
			(end 0.7874 -0.4064)
			(stroke
				(width 0.1524)
				(type default)
			)
			(layer "F.SilkS")
		)
		(fp_line
			(start 0.67945 0.3048)
			(end 0.120396 0.3048)
			(stroke
				(width 0.1)
				(type default)
			)
			(layer "F.Fab")
		)
		(fp_line
			(start 0.67945 -0.3048)
			(end 0.67945 0.3048)
			(stroke
				(width 0.1)
				(type default)
			)
			(layer "F.Fab")
		)
		(fp_line
			(start 0.12065 -0.2794)
			(end 0.12065 -0.3048)
			(stroke
				(width 0.1)
				(type default)
			)
			(layer "F.Fab")
		)
		(fp_line
			(start 0.12065 -0.3048)
			(end 0.67945 -0.3048)
			(stroke
				(width 0.1)
				(type default)
			)
			(layer "F.Fab")
		)
		(fp_line
			(start 0.120396 0.3048)
			(end 0.120396 0.2794)
			(stroke
				(width 0.1)
				(type default)
			)
			(layer "F.Fab")
		)
		(fp_line
			(start 0.120396 0.2794)
			(end -0.12065 0.2794)
			(stroke
				(width 0.1)
				(type default)
			)
			(layer "F.Fab")
		)
		(fp_line
			(start -0.12065 0.3048)
			(end -0.67945 0.3048)
			(stroke
				(width 0.1)
				(type default)
			)
			(layer "F.Fab")
		)
		(fp_line
			(start -0.12065 0.2794)
			(end -0.12065 0.3048)
			(stroke
				(width 0.1)
				(type default)
			)
			(layer "F.Fab")
		)
		(fp_line
			(start -0.12065 -0.2794)
			(end 0.12065 -0.2794)
			(stroke
				(width 0.1)
				(type default)
			)
			(layer "F.Fab")
		)
		(fp_line
			(start -0.12065 -0.305054)
			(end -0.12065 -0.2794)
			(stroke
				(width 0.1)
				(type default)
			)
			(layer "F.Fab")
		)
		(fp_line
			(start -0.67945 0.3048)
			(end -0.67945 -0.305054)
			(stroke
				(width 0.1)
				(type default)
			)
			(layer "F.Fab")
		)
		(fp_line
			(start -0.67945 -0.305054)
			(end -0.12065 -0.305054)
			(stroke
				(width 0.1)
				(type default)
			)
			(layer "F.Fab")
		)
		(pad "1" smd circle
			(at -0.40005 0 180)
			(size 0 0)
			(layers "F.Cu" "F.Mask" "F.Paste")
			(net "FM_SWB_PWRGD")
		)
		(pad "2" smd circle
			(at 0.40005 0 180)
			(size 0 0)
			(layers "F.Cu" "F.Mask" "F.Paste")
			(net "GND")
		)
	)
	(footprint ""
		(layer "F.Cu")
		(at 299.02023 -56.432196 180)
		(property "Reference" "R2980"
			(at 0 0 180)
			(layer "F.SilkS")
			(hide yes)
			(effects
				(font
					(size 1.27 1.27)
				)
			)
		)
		(property "Value" ""
			(at 0 0 180)
			(layer "F.Fab")
			(effects
				(font
					(size 1.27 1.27)
				)
			)
		)
		(duplicate_pad_numbers_are_jumpers no)
		(fp_line
			(start 0.7874 0.4064)
			(end -0.7874 0.4064)
			(stroke
				(width 0.1524)
				(type default)
			)
			(layer "F.SilkS")
		)
		(fp_line
			(start 0.7874 -0.4064)
			(end 0.7874 0.4064)
			(stroke
				(width 0.1524)
				(type default)
			)
			(layer "F.SilkS")
		)
		(fp_line
			(start -0.7874 0.4064)
			(end -0.7874 -0.4064)
			(stroke
				(width 0.1524)
				(type default)
			)
			(layer "F.SilkS")
		)
		(fp_line
			(start -0.7874 -0.4064)
			(end 0.7874 -0.4064)
			(stroke
				(width 0.1524)
				(type default)
			)
			(layer "F.SilkS")
		)
		(fp_line
			(start 0.67945 0.3048)
			(end 0.120396 0.3048)
			(stroke
				(width 0.1)
				(type default)
			)
			(layer "F.Fab")
		)
		(fp_line
			(start 0.67945 -0.3048)
			(end 0.67945 0.3048)
			(stroke
				(width 0.1)
				(type default)
			)
			(layer "F.Fab")
		)
		(fp_line
			(start 0.12065 -0.2794)
			(end 0.12065 -0.3048)
			(stroke
				(width 0.1)
				(type default)
			)
			(layer "F.Fab")
		)
		(fp_line
			(start 0.12065 -0.3048)
			(end 0.67945 -0.3048)
			(stroke
				(width 0.1)
				(type default)
			)
			(layer "F.Fab")
		)
		(fp_line
			(start 0.120396 0.3048)
			(end 0.120396 0.2794)
			(stroke
				(width 0.1)
				(type default)
			)
			(layer "F.Fab")
		)
		(fp_line
			(start 0.120396 0.2794)
			(end -0.12065 0.2794)
			(stroke
				(width 0.1)
				(type default)
			)
			(layer "F.Fab")
		)
		(fp_line
			(start -0.12065 0.3048)
			(end -0.67945 0.3048)
			(stroke
				(width 0.1)
				(type default)
			)
			(layer "F.Fab")
		)
		(fp_line
			(start -0.12065 0.2794)
			(end -0.12065 0.3048)
			(stroke
				(width 0.1)
				(type default)
			)
			(layer "F.Fab")
		)
		(fp_line
			(start -0.12065 -0.2794)
			(end 0.12065 -0.2794)
			(stroke
				(width 0.1)
				(type default)
			)
			(layer "F.Fab")
		)
		(fp_line
			(start -0.12065 -0.305054)
			(end -0.12065 -0.2794)
			(stroke
				(width 0.1)
				(type default)
			)
			(layer "F.Fab")
		)
		(fp_line
			(start -0.67945 0.3048)
			(end -0.67945 -0.305054)
			(stroke
				(width 0.1)
				(type default)
			)
			(layer "F.Fab")
		)
		(fp_line
			(start -0.67945 -0.305054)
			(end -0.12065 -0.305054)
			(stroke
				(width 0.1)
				(type default)
			)
			(layer "F.Fab")
		)
		(pad "1" smd circle
			(at -0.40005 0 180)
			(size 0 0)
			(layers "F.Cu" "F.Mask" "F.Paste")
			(net "FM_BOARD_SKU_ID2")
		)
		(pad "2" smd circle
			(at 0.40005 0 180)
			(size 0 0)
			(layers "F.Cu" "F.Mask" "F.Paste")
			(net "GND")
		)
	)
)
